# T6G (Grand Teton) — schematic netlist excerpt (pin names and nets, part order shuffled) for the footprints in the layout excerpt that follows; sources: Cadence DE-HDL packaged netlist, KiCad conversion of 04192023_DAF0TMB3IC0_F0TG_MB_C_brd_V02_OCP.brd

U158  MOSFET_NCH_GDS_ESD_PROTECTED  2N7002K IC  pkg SOT23_GDSXC  page 242
  D  = FM_P12V_HSC_EN_N
  G  = FM_P12V_HSC_EN_R
  S  = GND

C6007  Q_CAP  0.1UF 25V 10% X7R  pkg 0402  page 113 : A = P2E_MB_BMC_RX_BUF2_C_DP<0> ; B = P2E_MB_BMC_RX_BUF_DP<0>

(kicad_pcb
	(version 20260206)
	(generator "pcbnew")
	(generator_version "10.0")
	(general
		(thickness 1.6)
		(legacy_teardrops no)
	)
	(paper "A4")
	(title_block
		(title "04192023_DAF0TMB3IC0_F0TG_MB_C_brd_V02_OCP.brd")
		(comment 1 "Grand Teton / footprints 2229-2230 of 8354")
	)
	(layers
		(0 "F.Cu" signal "TOP")
		(4 "In1.Cu" signal "GND")
		(6 "In2.Cu" signal "IN1")
		(8 "In3.Cu" signal "GND1")
		(10 "In4.Cu" signal "IN2")
		(12 "In5.Cu" signal "GND2")
		(14 "In6.Cu" signal "IN3")
		(16 "In7.Cu" signal "GND3")
		(18 "In8.Cu" signal "VCC")
		(20 "In9.Cu" signal "VCC1")
		(22 "In10.Cu" signal "GND4")
		(24 "In11.Cu" signal "IN4")
		(26 "In12.Cu" signal "GND5")
		(28 "In13.Cu" signal "IN5")
		(30 "In14.Cu" signal "GND6")
		(32 "In15.Cu" signal "IN6")
		(34 "In16.Cu" signal "GND7")
		(2 "B.Cu" signal "BOTTOM")
		(9 "F.Adhes" user "F.Adhesive")
		(11 "B.Adhes" user "B.Adhesive")
		(13 "F.Paste" user "Package Geometry/Pastemask Top")
		(15 "B.Paste" user "Package Geometry/Pastemask Bottom")
		(5 "F.SilkS" user "Ref Des/Silkscreen Top")
		(7 "B.SilkS" user "Ref Des/Silkscreen Bottom")
		(1 "F.Mask" user "Board Geometry/Soldermask Top")
		(3 "B.Mask" user "Board Geometry/Soldermask Bottom")
		(17 "Dwgs.User" user "User.Drawings")
		(19 "Cmts.User" user "User.Comments")
		(21 "Eco1.User" user "User.Eco1")
		(23 "Eco2.User" user "User.Eco2")
		(25 "Edge.Cuts" user "Board Geometry/Outline")
		(27 "Margin" user)
		(31 "F.CrtYd" user "Package Geometry/Place Bound Top")
		(29 "B.CrtYd" user "Package Geometry/Place Bound Bottom")
		(35 "F.Fab" user "Ref Des/Assembly Top")
		(33 "B.Fab" user "Ref Des/Assembly Bottom")
	)
	(footprint ""
		(layer "F.Cu")
		(at 209.78622 -137.127488 180)
		(property "Reference" "U158"
			(at -0.62992 2.298192 0)
			(unlocked yes)
			(layer "F.SilkS")
			(effects
				(font
					(size 0.7874 0.5842)
					(thickness 0.1524)
				)
				(justify left)
			)
		)
		(property "Value" ""
			(at 0 0 180)
			(layer "F.Fab")
			(effects
				(font
					(size 1.27 1.27)
				)
			)
		)
		(duplicate_pad_numbers_are_jumpers no)
		(fp_line
			(start 1.603248 1.500124)
			(end -1.603248 1.500124)
			(stroke
				(width 0.1524)
				(type default)
			)
			(layer "F.SilkS")
		)
		(fp_line
			(start 1.603248 -1.500124)
			(end 1.603248 1.500124)
			(stroke
				(width 0.1524)
				(type default)
			)
			(layer "F.SilkS")
		)
		(fp_line
			(start -1.603248 1.500124)
			(end -1.603248 -1.500124)
			(stroke
				(width 0.1524)
				(type default)
			)
			(layer "F.SilkS")
		)
		(fp_line
			(start -1.603248 -1.500124)
			(end 1.603248 -1.500124)
			(stroke
				(width 0.1524)
				(type default)
			)
			(layer "F.SilkS")
		)
		(fp_line
			(start 1.249934 0.219964)
			(end 1.249934 -0.219964)
			(stroke
				(width 0.1)
				(type default)
			)
			(layer "F.Fab")
		)
		(fp_line
			(start 1.249934 -0.219964)
			(end 0.700024 -0.219964)
			(stroke
				(width 0.1)
				(type default)
			)
			(layer "F.Fab")
		)
		(fp_line
			(start 0.700024 1.500124)
			(end 0.700024 0.219964)
			(stroke
				(width 0.1)
				(type default)
			)
			(layer "F.Fab")
		)
		(fp_line
			(start 0.700024 0.219964)
			(end 1.249934 0.219964)
			(stroke
				(width 0.1)
				(type default)
			)
			(layer "F.Fab")
		)
		(fp_line
			(start 0.700024 -0.219964)
			(end 0.700024 -1.500124)
			(stroke
				(width 0.1)
				(type default)
			)
			(layer "F.Fab")
		)
		(fp_line
			(start 0.700024 -1.500124)
			(end -0.700024 -1.500124)
			(stroke
				(width 0.1)
				(type default)
			)
			(layer "F.Fab")
		)
		(fp_line
			(start -0.6985 0.729996)
			(end -1.249934 0.729996)
			(stroke
				(width 0.1)
				(type default)
			)
			(layer "F.Fab")
		)
		(fp_line
			(start -0.6985 -0.729996)
			(end -0.6985 0.729996)
			(stroke
				(width 0.1)
				(type default)
			)
			(layer "F.Fab")
		)
		(fp_line
			(start -0.700024 1.500124)
			(end 0.700024 1.500124)
			(stroke
				(width 0.1)
				(type default)
			)
			(layer "F.Fab")
		)
		(fp_line
			(start -0.700024 1.169924)
			(end -0.700024 1.500124)
			(stroke
				(width 0.1)
				(type default)
			)
			(layer "F.Fab")
		)
		(fp_line
			(start -0.700024 -1.169924)
			(end -1.249934 -1.169924)
			(stroke
				(width 0.1)
				(type default)
			)
			(layer "F.Fab")
		)
		(fp_line
			(start -0.700024 -1.500124)
			(end -0.700024 -1.169924)
			(stroke
				(width 0.1)
				(type default)
			)
			(layer "F.Fab")
		)
		(fp_line
			(start -1.249934 1.169924)
			(end -0.700024 1.169924)
			(stroke
				(width 0.1)
				(type default)
			)
			(layer "F.Fab")
		)
		(fp_line
			(start -1.249934 0.729996)
			(end -1.249934 1.169924)
			(stroke
				(width 0.1)
				(type default)
			)
			(layer "F.Fab")
		)
		(fp_line
			(start -1.249934 -0.729996)
			(end -0.6985 -0.729996)
			(stroke
				(width 0.1)
				(type default)
			)
			(layer "F.Fab")
		)
		(fp_line
			(start -1.249934 -1.169924)
			(end -1.249934 -0.729996)
			(stroke
				(width 0.1)
				(type default)
			)
			(layer "F.Fab")
		)
		(fp_rect
			(start 0.700024 -1.500124)
			(end -0.700024 1.500124)
			(stroke
				(width 0)
				(type default)
			)
			(fill no)
			(layer "F.Fab")
		)
		(pad "D" smd rect
			(at 0.999998 0 90)
			(size 0.8128 0.9144)
			(layers "F.Cu" "F.Mask" "F.Paste")
			(net "FM_P12V_HSC_EN_N")
		)
		(pad "G" smd rect
			(at -0.999998 -0.94996 90)
			(size 0.8128 0.9144)
			(layers "F.Cu" "F.Mask" "F.Paste")
			(net "FM_P12V_HSC_EN_R")
		)
		(pad "S" smd rect
			(at -0.999998 0.94996 90)
			(size 0.8128 0.9144)
			(layers "F.Cu" "F.Mask" "F.Paste")
			(net "GND")
		)
	)
	(footprint ""
		(layer "F.Cu")
		(at 39.95039 -426.563536 180)
		(property "Reference" "C6007"
			(at 0 0 180)
			(layer "F.SilkS")
			(hide yes)
			(effects
				(font
					(size 1.27 1.27)
				)
			)
		)
		(property "Value" ""
			(at 0 0 180)
			(layer "F.Fab")
			(effects
				(font
					(size 1.27 1.27)
				)
			)
		)
		(duplicate_pad_numbers_are_jumpers no)
		(fp_line
			(start 0.7874 0.4064)
			(end -0.7874 0.4064)
			(stroke
				(width 0.1524)
				(type default)
			)
			(layer "F.SilkS")
		)
		(fp_line
			(start 0.7874 -0.275336)
			(end 0.7874 0.4064)
			(stroke
				(width 0.1524)
				(type default)
			)
			(layer "F.SilkS")
		)
		(fp_line
			(start -0.7874 -0.4064)
			(end -0.35941 -0.4064)
			(stroke
				(width 0.1524)
				(type default)
			)
			(layer "F.SilkS")
		)
		(fp_line
			(start 0.6858 0.3048)
			(end 0.1016 0.3048)
			(stroke
				(width 0.1)
				(type default)
			)
			(layer "F.Fab")
		)
		(fp_line
			(start 0.6858 -0.3048)
			(end 0.6858 0.3048)
			(stroke
				(width 0.1)
				(type default)
			)
			(layer "F.Fab")
		)
		(fp_line
			(start 0.1016 0.3048)
			(end 0.1016 0.2794)
			(stroke
				(width 0.1)
				(type default)
			)
			(layer "F.Fab")
		)
		(fp_line
			(start 0.1016 0.2794)
			(end -0.1016 0.2794)
			(stroke
				(width 0.1)
				(type default)
			)
			(layer "F.Fab")
		)
		(fp_line
			(start 0.1016 -0.2794)
			(end 0.1016 -0.3048)
			(stroke
				(width 0.1)
				(type default)
			)
			(layer "F.Fab")
		)
		(fp_line
			(start 0.1016 -0.3048)
			(end 0.6858 -0.3048)
			(stroke
				(width 0.1)
				(type default)
			)
			(layer "F.Fab")
		)
		(fp_line
			(start -0.1016 0.3048)
			(end -0.6858 0.3048)
			(stroke
				(width 0.1)
				(type default)
			)
			(layer "F.Fab")
		)
		(fp_line
			(start -0.1016 0.2794)
			(end -0.1016 0.3048)
			(stroke
				(width 0.1)
				(type default)
			)
			(layer "F.Fab")
		)
		(fp_line
			(start -0.1016 -0.2794)
			(end 0.1016 -0.2794)
			(stroke
				(width 0.1)
				(type default)
			)
			(layer "F.Fab")
		)
		(fp_line
			(start -0.1016 -0.3048)
			(end -0.1016 -0.2794)
			(stroke
				(width 0.1)
				(type default)
			)
			(layer "F.Fab")
		)
		(fp_line
			(start -0.6858 0.3048)
			(end -0.6858 -0.3048)
			(stroke
				(width 0.1)
				(type default)
			)
			(layer "F.Fab")
		)
		(fp_line
			(start -0.6858 -0.3048)
			(end -0.1016 -0.3048)
			(stroke
				(width 0.1)
				(type default)
			)
			(layer "F.Fab")
		)
		(pad "1" smd rect
			(at -0.40005 0)
			(size 0.4572 0.508)
			(layers "F.Cu" "F.Mask" "F.Paste")
			(net "P2E_MB_BMC_RX_BUF2_C_DP<0>")
		)
		(pad "2" smd rect
			(at 0.40005 0)
			(size 0.4572 0.508)
			(layers "F.Cu" "F.Mask" "F.Paste")
			(net "P2E_MB_BMC_RX_BUF_DP<0>")
		)
	)
)
